(kicad_pcb
	(version 20260206)
	(generator "pcbnew")
	(generator_version "10.0")
	(general
		(thickness 1.6)
		(legacy_teardrops no)
	)
	(paper "A4")
	(title_block
		(title "peb — Lightning_PEB_BRD.brd")
		(comment 1 "Lightning (Wiwynn / Facebook NVMe JBOF) / footprints 1632-1638 of 2563")
	)
	(layers
		(0 "F.Cu" signal "TOP")
		(4 "In1.Cu" signal "L2GND")
		(6 "In2.Cu" signal "L3")
		(8 "In3.Cu" signal "L4VCC")
		(10 "In4.Cu" signal "L5VCC")
		(12 "In5.Cu" signal "L6")
		(14 "In6.Cu" signal "L7GND")
		(2 "B.Cu" signal "BOTTOM")
		(9 "F.Adhes" user "F.Adhesive")
		(11 "B.Adhes" user "B.Adhesive")
		(13 "F.Paste" user "Package Geometry/Pastemask Top")
		(15 "B.Paste" user "Package Geometry/Pastemask Bottom")
		(5 "F.SilkS" user "Ref Des/Silkscreen Top")
		(7 "B.SilkS" user "Ref Des/Silkscreen Bottom")
		(1 "F.Mask" user "Board Geometry/Soldermask Top")
		(3 "B.Mask" user "Board Geometry/Soldermask Bottom")
		(17 "Dwgs.User" user "User.Drawings")
		(19 "Cmts.User" user "User.Comments")
		(21 "Eco1.User" user "User.Eco1")
		(23 "Eco2.User" user "User.Eco2")
		(25 "Edge.Cuts" user "Board Geometry/Outline")
		(27 "Margin" user)
		(31 "F.CrtYd" user "Package Geometry/Place Bound Top")
		(29 "B.CrtYd" user "Package Geometry/Place Bound Bottom")
		(35 "F.Fab" user "Ref Des/Assembly Top")
		(33 "B.Fab" user "Ref Des/Assembly Bottom")
	)
	(footprint ""
		(layer "F.Cu")
		(at 56.604916 -37.785294)
		(property "Reference" "Q43"
			(at 0 0 0)
			(layer "F.SilkS")
			(hide yes)
			(effects
				(font
					(size 1.27 1.27)
				)
			)
		)
		(property "Value" "DSS4240T-7-GP"
			(at 0.10287 -10.29843 0)
			(unlocked yes)
			(layer "F.Fab")
			(hide yes)
			(effects
				(font
					(size 1.016 1.016)
					(thickness 0.1524)
				)
			)
		)
		(property "Device Type" "SOT23CBE2D4H44"
			(at 0.10287 -12.20343 0)
			(unlocked yes)
			(layer "F.Fab")
			(hide yes)
			(effects
				(font
					(size 1.016 1.016)
					(thickness 0.1524)
				)
			)
		)
		(duplicate_pad_numbers_are_jumpers no)
		(fp_line
			(start -1.651 -1.778)
			(end -1.651 1.778)
			(stroke
				(width 0.1524)
				(type default)
			)
			(layer "F.SilkS")
		)
		(fp_line
			(start -1.651 1.778)
			(end 1.651 1.778)
			(stroke
				(width 0.1524)
				(type default)
			)
			(layer "F.SilkS")
		)
		(fp_line
			(start 1.651 -1.778)
			(end -1.651 -1.778)
			(stroke
				(width 0.1524)
				(type default)
			)
			(layer "F.SilkS")
		)
		(fp_line
			(start 1.651 1.778)
			(end 1.651 -1.778)
			(stroke
				(width 0.1524)
				(type default)
			)
			(layer "F.SilkS")
		)
		(fp_poly
			(pts
				(xy -1.778 1.8796) (xy -1.778 -1.8796) (xy 1.778 -1.8796) (xy 1.778 1.8796)
			)
			(stroke
				(width 0)
				(type default)
			)
			(fill no)
			(layer "F.CrtYd")
		)
		(fp_poly
			(pts
				(xy -1.778 1.8796) (xy -1.778 -1.8796) (xy 1.778 -1.8796) (xy 1.778 1.8796)
			)
			(stroke
				(width 0)
				(type default)
			)
			(fill no)
			(layer "F.Fab")
		)
		(pad "B" smd custom
			(at -0.98425 0.9525)
			(size 0.1905 0.1905)
			(layers "F.Cu" "F.Mask" "F.Paste")
			(net "Q43_B")
			(options
				(clearance outline)
				(anchor circle)
			)
			(primitives
				(gr_poly
					(pts
						(arc
							(start -0.1778 0.5715)
							(mid -0.321484 0.511984)
							(end -0.381 0.3683)
						)
						(arc
							(start -0.381 -0.3683)
							(mid -0.321484 -0.511984)
							(end -0.1778 -0.5715)
						)
						(arc
							(start 0.1778 -0.5715)
							(mid 0.321484 -0.511984)
							(end 0.381 -0.3683)
						)
						(arc
							(start 0.381 0.3683)
							(mid 0.321484 0.511984)
							(end 0.1778 0.5715)
						)
					)
					(width 0)
					(fill yes)
				)
			)
		)
		(pad "C" smd custom
			(at 0 -0.9525)
			(size 0.1905 0.1905)
			(layers "F.Cu" "F.Mask" "F.Paste")
			(net "Q43_C")
			(options
				(clearance outline)
				(anchor circle)
			)
			(primitives
				(gr_poly
					(pts
						(arc
							(start -0.1778 0.5715)
							(mid -0.321484 0.511984)
							(end -0.381 0.3683)
						)
						(arc
							(start -0.381 -0.3683)
							(mid -0.321484 -0.511984)
							(end -0.1778 -0.5715)
						)
						(arc
							(start 0.1778 -0.5715)
							(mid 0.321484 -0.511984)
							(end 0.381 -0.3683)
						)
						(arc
							(start 0.381 0.3683)
							(mid 0.321484 0.511984)
							(end 0.1778 0.5715)
						)
					)
					(width 0)
					(fill yes)
				)
			)
		)
		(pad "E" smd custom
			(at 0.98425 0.9525)
			(size 0.1905 0.1905)
			(layers "F.Cu" "F.Mask" "F.Paste")
			(net "GND")
			(options
				(clearance outline)
				(anchor circle)
			)
			(primitives
				(gr_poly
					(pts
						(arc
							(start -0.1778 0.5715)
							(mid -0.321484 0.511984)
							(end -0.381 0.3683)
						)
						(arc
							(start -0.381 -0.3683)
							(mid -0.321484 -0.511984)
							(end -0.1778 -0.5715)
						)
						(arc
							(start 0.1778 -0.5715)
							(mid 0.321484 -0.511984)
							(end 0.381 -0.3683)
						)
						(arc
							(start 0.381 0.3683)
							(mid 0.321484 0.511984)
							(end 0.1778 0.5715)
						)
					)
					(width 0)
					(fill yes)
				)
			)
		)
	)
	(footprint ""
		(layer "F.Cu")
		(at 328.835512 -184.878218 180)
		(property "Reference" "C417"
			(at 0 0 180)
			(layer "F.SilkS")
			(hide yes)
			(effects
				(font
					(size 1.27 1.27)
				)
			)
		)
		(property "Value" "SCD1U25V2KX-2-GP"
			(at 1.1811 -2.7051 180)
			(unlocked yes)
			(layer "F.Fab")
			(hide yes)
			(effects
				(font
					(size 1.016 1.016)
					(thickness 0.1524)
				)
			)
		)
		(property "Device Type" "C402H22"
			(at 1.1811 -4.2291 180)
			(unlocked yes)
			(layer "F.Fab")
			(hide yes)
			(effects
				(font
					(size 1.016 1.016)
					(thickness 0.1524)
				)
			)
		)
		(duplicate_pad_numbers_are_jumpers no)
		(fp_rect
			(start -0.4318 0.9525)
			(end 0.4318 -0.9525)
			(stroke
				(width 0)
				(type default)
			)
			(fill no)
			(layer "F.CrtYd")
		)
		(fp_rect
			(start -0.4318 0.9525)
			(end 0.4318 -0.9525)
			(stroke
				(width 0)
				(type default)
			)
			(fill no)
			(layer "F.Fab")
		)
		(pad "1" smd custom
			(at 0 -0.4445 180)
			(size 0.1524 0.1524)
			(layers "F.Cu" "F.Mask" "F.Paste")
			(net "P3V3_STBY")
			(options
				(clearance outline)
				(anchor circle)
			)
			(primitives
				(gr_poly
					(pts
						(arc
							(start 0.3048 -0.2032)
							(mid 0.275042 -0.275042)
							(end 0.2032 -0.3048)
						)
						(arc
							(start -0.2032 -0.3048)
							(mid -0.275042 -0.275042)
							(end -0.3048 -0.2032)
						)
						(arc
							(start -0.3048 0.2032)
							(mid -0.275042 0.275042)
							(end -0.2032 0.3048)
						)
						(arc
							(start 0.2032 0.3048)
							(mid 0.275042 0.275042)
							(end 0.3048 0.2032)
						)
					)
					(width 0)
					(fill yes)
				)
			)
		)
		(pad "2" smd custom
			(at 0 0.4445 180)
			(size 0.1524 0.1524)
			(layers "F.Cu" "F.Mask" "F.Paste")
			(net "GND")
			(options
				(clearance outline)
				(anchor circle)
			)
			(primitives
				(gr_poly
					(pts
						(arc
							(start 0.3048 -0.2032)
							(mid 0.275042 -0.275042)
							(end 0.2032 -0.3048)
						)
						(arc
							(start -0.2032 -0.3048)
							(mid -0.275042 -0.275042)
							(end -0.3048 -0.2032)
						)
						(arc
							(start -0.3048 0.2032)
							(mid -0.275042 0.275042)
							(end -0.2032 0.3048)
						)
						(arc
							(start 0.2032 0.3048)
							(mid 0.275042 0.275042)
							(end 0.3048 0.2032)
						)
					)
					(width 0)
					(fill yes)
				)
			)
		)
	)
	(footprint ""
		(layer "F.Cu")
		(at 330.099924 -1.999996 -90)
		(property "Reference" "LED16"
			(at 0 0 270)
			(layer "F.SilkS")
			(hide yes)
			(effects
				(font
					(size 1.27 1.27)
				)
			)
		)
		(property "Value" "LED-YG-51-GP"
			(at -2.6924 -1.4224 270)
			(unlocked yes)
			(layer "F.Fab")
			(hide yes)
			(effects
				(font
					(size 1.016 1.016)
					(thickness 0.1524)
				)
			)
		)
		(property "Device Type" "LED1608AKH40"
			(at -2.6924 -2.9464 270)
			(unlocked yes)
			(layer "F.Fab")
			(hide yes)
			(effects
				(font
					(size 1.016 1.016)
					(thickness 0.1524)
				)
			)
		)
		(duplicate_pad_numbers_are_jumpers no)
		(fp_line
			(start -0.7493 1.651)
			(end -0.7493 1.1811)
			(stroke
				(width 0.3302)
				(type default)
			)
			(layer "F.SilkS")
		)
		(fp_line
			(start 0.7493 1.651)
			(end 0.7493 1.1811)
			(stroke
				(width 0.3302)
				(type default)
			)
			(layer "F.SilkS")
		)
		(fp_line
			(start -0.5969 1.5494)
			(end 0.5842 1.5494)
			(stroke
				(width 0.508)
				(type default)
			)
			(layer "F.SilkS")
		)
		(fp_line
			(start -0.6604 1.3716)
			(end -0.6604 -1.3716)
			(stroke
				(width 0.1524)
				(type default)
			)
			(layer "F.SilkS")
		)
		(fp_line
			(start 0.6604 1.3716)
			(end -0.6604 1.3716)
			(stroke
				(width 0.1524)
				(type default)
			)
			(layer "F.SilkS")
		)
		(fp_line
			(start -0.6604 -1.3716)
			(end 0.6604 -1.3716)
			(stroke
				(width 0.1524)
				(type default)
			)
			(layer "F.SilkS")
		)
		(fp_line
			(start 0.6604 -1.3716)
			(end 0.6604 1.3716)
			(stroke
				(width 0.1524)
				(type default)
			)
			(layer "F.SilkS")
		)
		(fp_rect
			(start -0.6223 1.3335)
			(end 0.6223 -1.3335)
			(stroke
				(width 0)
				(type default)
			)
			(fill no)
			(layer "F.CrtYd")
		)
		(fp_rect
			(start -0.6223 1.3335)
			(end 0.6223 -1.3335)
			(stroke
				(width 0)
				(type default)
			)
			(fill no)
			(layer "F.Fab")
		)
		(pad "A" smd custom
			(at 0 -0.762 270)
			(size 0.2159 0.2159)
			(layers "F.Cu" "F.Mask" "F.Paste")
			(net "LED_R_8")
			(options
				(clearance outline)
				(anchor circle)
			)
			(primitives
				(gr_poly
					(pts
						(arc
							(start -0.3302 -0.4318)
							(mid -0.402042 -0.402042)
							(end -0.4318 -0.3302)
						)
						(arc
							(start -0.4318 0.3302)
							(mid -0.402042 0.402042)
							(end -0.3302 0.4318)
						)
						(arc
							(start 0.3302 0.4318)
							(mid 0.402042 0.402042)
							(end 0.4318 0.3302)
						)
						(arc
							(start 0.4318 -0.3302)
							(mid 0.402042 -0.402042)
							(end 0.3302 -0.4318)
						)
					)
					(width 0)
					(fill yes)
				)
			)
		)
		(pad "K" smd custom
			(at 0 0.762 270)
			(size 0.2159 0.2159)
			(layers "F.Cu" "F.Mask" "F.Paste")
			(net "LED_Q_8")
			(options
				(clearance outline)
				(anchor circle)
			)
			(primitives
				(gr_poly
					(pts
						(arc
							(start -0.3302 -0.4318)
							(mid -0.402042 -0.402042)
							(end -0.4318 -0.3302)
						)
						(arc
							(start -0.4318 0.3302)
							(mid -0.402042 0.402042)
							(end -0.3302 0.4318)
						)
						(arc
							(start 0.3302 0.4318)
							(mid 0.402042 0.402042)
							(end 0.4318 0.3302)
						)
						(arc
							(start 0.4318 -0.3302)
							(mid 0.402042 -0.402042)
							(end 0.3302 -0.4318)
						)
					)
					(width 0)
					(fill yes)
				)
			)
		)
	)
	(footprint ""
		(layer "F.Cu")
		(at 183.073802 0.9271 90)
		(property "Reference" "SLED28"
			(at 0 0 90)
			(layer "F.SilkS")
			(hide yes)
			(effects
				(font
					(size 1.27 1.27)
				)
			)
		)
		(property "Value" "LED-YG-51-GP"
			(at -2.6924 -1.4224 90)
			(unlocked yes)
			(layer "F.Fab")
			(hide yes)
			(effects
				(font
					(size 1.016 1.016)
					(thickness 0.1524)
				)
			)
		)
		(property "Device Type" "LED1608AKH40"
			(at -2.6924 -2.9464 90)
			(unlocked yes)
			(layer "F.Fab")
			(hide yes)
			(effects
				(font
					(size 1.016 1.016)
					(thickness 0.1524)
				)
			)
		)
		(duplicate_pad_numbers_are_jumpers no)
		(fp_line
			(start 0.6604 -1.3716)
			(end 0.6604 1.3716)
			(stroke
				(width 0.1524)
				(type default)
			)
			(layer "F.SilkS")
		)
		(fp_line
			(start -0.6604 -1.3716)
			(end 0.6604 -1.3716)
			(stroke
				(width 0.1524)
				(type default)
			)
			(layer "F.SilkS")
		)
		(fp_line
			(start 0.6604 1.3716)
			(end -0.6604 1.3716)
			(stroke
				(width 0.1524)
				(type default)
			)
			(layer "F.SilkS")
		)
		(fp_line
			(start -0.6604 1.3716)
			(end -0.6604 -1.3716)
			(stroke
				(width 0.1524)
				(type default)
			)
			(layer "F.SilkS")
		)
		(fp_line
			(start -0.5969 1.5494)
			(end 0.5842 1.5494)
			(stroke
				(width 0.508)
				(type default)
			)
			(layer "F.SilkS")
		)
		(fp_line
			(start 0.7493 1.651)
			(end 0.7493 1.1811)
			(stroke
				(width 0.3302)
				(type default)
			)
			(layer "F.SilkS")
		)
		(fp_line
			(start -0.7493 1.651)
			(end -0.7493 1.1811)
			(stroke
				(width 0.3302)
				(type default)
			)
			(layer "F.SilkS")
		)
		(fp_rect
			(start -0.6223 1.3335)
			(end 0.6223 -1.3335)
			(stroke
				(width 0)
				(type default)
			)
			(fill no)
			(layer "F.CrtYd")
		)
		(fp_rect
			(start -0.6223 1.3335)
			(end 0.6223 -1.3335)
			(stroke
				(width 0)
				(type default)
			)
			(fill no)
			(layer "F.Fab")
		)
		(pad "A" smd custom
			(at 0 -0.762 90)
			(size 0.2159 0.2159)
			(layers "F.Cu" "F.Mask" "F.Paste")
			(net "EXP_BMC_HB_LED_R")
			(options
				(clearance outline)
				(anchor circle)
			)
			(primitives
				(gr_poly
					(pts
						(arc
							(start -0.3302 -0.4318)
							(mid -0.402042 -0.402042)
							(end -0.4318 -0.3302)
						)
						(arc
							(start -0.4318 0.3302)
							(mid -0.402042 0.402042)
							(end -0.3302 0.4318)
						)
						(arc
							(start 0.3302 0.4318)
							(mid 0.402042 0.402042)
							(end 0.4318 0.3302)
						)
						(arc
							(start 0.4318 -0.3302)
							(mid 0.402042 -0.402042)
							(end 0.3302 -0.4318)
						)
					)
					(width 0)
					(fill yes)
				)
			)
		)
		(pad "K" smd custom
			(at 0 0.762 90)
			(size 0.2159 0.2159)
			(layers "F.Cu" "F.Mask" "F.Paste")
			(net "EXP_BMC_HB_LED_D")
			(options
				(clearance outline)
				(anchor circle)
			)
			(primitives
				(gr_poly
					(pts
						(arc
							(start -0.3302 -0.4318)
							(mid -0.402042 -0.402042)
							(end -0.4318 -0.3302)
						)
						(arc
							(start -0.4318 0.3302)
							(mid -0.402042 0.402042)
							(end -0.3302 0.4318)
						)
						(arc
							(start 0.3302 0.4318)
							(mid 0.402042 0.402042)
							(end 0.4318 0.3302)
						)
						(arc
							(start 0.4318 -0.3302)
							(mid 0.402042 -0.402042)
							(end 0.3302 -0.4318)
						)
					)
					(width 0)
					(fill yes)
				)
			)
		)
	)
	(footprint ""
		(layer "F.Cu")
		(at 18.7452 -53.6194 180)
		(property "Reference" "R582"
			(at 0 0 180)
			(layer "F.SilkS")
			(hide yes)
			(effects
				(font
					(size 1.27 1.27)
				)
			)
		)
		(property "Value" "0R2J-2-GP"
			(at 0.064008 -3.993896 180)
			(unlocked yes)
			(layer "F.Fab")
			(hide yes)
			(effects
				(font
					(size 1.016 1.016)
					(thickness 0.1524)
				)
			)
		)
		(property "Device Type" "R402H16"
			(at 0.064008 -5.517896 180)
			(unlocked yes)
			(layer "F.Fab")
			(hide yes)
			(effects
				(font
					(size 1.016 1.016)
					(thickness 0.1524)
				)
			)
		)
		(duplicate_pad_numbers_are_jumpers no)
		(fp_line
			(start 0.508 -0.9398)
			(end -0.508 -0.9398)
			(stroke
				(width 0.1524)
				(type default)
			)
			(layer "F.SilkS")
		)
		(fp_line
			(start -0.508 -0.9398)
			(end -0.508 0.9398)
			(stroke
				(width 0.1524)
				(type default)
			)
			(layer "F.SilkS")
		)
		(fp_rect
			(start -0.508 0.9398)
			(end 0.508 -0.9398)
			(stroke
				(width 0)
				(type default)
			)
			(fill no)
			(layer "F.CrtYd")
		)
		(fp_rect
			(start -0.508 0.9398)
			(end 0.508 -0.9398)
			(stroke
				(width 0)
				(type default)
			)
			(fill no)
			(layer "F.Fab")
		)
		(pad "1" smd custom
			(at 0 -0.4445 180)
			(size 0.1397 0.1397)
			(layers "F.Cu" "F.Mask" "F.Paste")
			(net "NIC0_MDI0_P2_R")
			(options
				(clearance outline)
				(anchor circle)
			)
			(primitives
				(gr_poly
					(pts
						(arc
							(start -0.1778 -0.2794)
							(mid -0.249642 -0.249642)
							(end -0.2794 -0.1778)
						)
						(arc
							(start -0.2794 0.1778)
							(mid -0.249642 0.249642)
							(end -0.1778 0.2794)
						)
						(arc
							(start 0.1778 0.2794)
							(mid 0.249642 0.249642)
							(end 0.2794 0.1778)
						)
						(arc
							(start 0.2794 -0.1778)
							(mid 0.249642 -0.249642)
							(end 0.1778 -0.2794)
						)
					)
					(width 0)
					(fill yes)
				)
			)
		)
		(pad "2" smd custom
			(at 0 0.4445 180)
			(size 0.1397 0.1397)
			(layers "F.Cu" "F.Mask" "F.Paste")
			(net "NIC0_MDI0_P2")
			(options
				(clearance outline)
				(anchor circle)
			)
			(primitives
				(gr_poly
					(pts
						(arc
							(start -0.1778 -0.2794)
							(mid -0.249642 -0.249642)
							(end -0.2794 -0.1778)
						)
						(arc
							(start -0.2794 0.1778)
							(mid -0.249642 0.249642)
							(end -0.1778 0.2794)
						)
						(arc
							(start 0.1778 0.2794)
							(mid 0.249642 0.249642)
							(end 0.2794 0.1778)
						)
						(arc
							(start 0.2794 -0.1778)
							(mid 0.249642 -0.249642)
							(end 0.1778 -0.2794)
						)
					)
					(width 0)
					(fill yes)
				)
			)
		)
	)
	(footprint ""
		(layer "F.Cu")
		(at 14.224 -113.411 90)
		(property "Reference" "PG12"
			(at 0 0 90)
			(layer "F.SilkS")
			(hide yes)
			(effects
				(font
					(size 1.27 1.27)
				)
			)
		)
		(property "Value" "GAP-CLOSE-PWR-3-GP"
			(at 0.0254 -6.5786 90)
			(unlocked yes)
			(layer "F.Fab")
			(hide yes)
			(effects
				(font
					(size 1.016 1.016)
					(thickness 0.1524)
				)
			)
		)
		(property "Device Type" "GAP-CLOSE-PWR-3"
			(at 0.0254 -8.255 90)
			(unlocked yes)
			(layer "F.Fab")
			(hide yes)
			(effects
				(font
					(size 1.016 1.016)
					(thickness 0.1524)
				)
			)
		)
		(duplicate_pad_numbers_are_jumpers no)
		(fp_rect
			(start -0.7112 0.4572)
			(end 0.7112 -0.4572)
			(stroke
				(width 0)
				(type default)
			)
			(fill no)
			(layer "F.CrtYd")
		)
		(fp_poly
			(pts
				(xy -0.7112 -0.4572) (xy 0.7112 -0.4572) (xy 0.7112 0.4572) (xy -0.7112 0.4572)
			)
			(stroke
				(width 0)
				(type default)
			)
			(fill no)
			(layer "F.Fab")
		)
		(pad "1" smd rect
			(at -0.3048 0 90)
			(size 0.6604 0.762)
			(layers "F.Cu" "F.Mask" "F.Paste")
			(net "P1V26_PWR")
		)
		(pad "2" smd rect
			(at 0.3048 0 90)
			(size 0.6604 0.762)
			(layers "F.Cu" "F.Mask" "F.Paste")
			(net "P1V26_STBY")
		)
	)
	(footprint ""
		(layer "F.Cu")
		(at 287.808162 -212.420454 180)
		(property "Reference" "C92"
			(at 0 0 180)
			(layer "F.SilkS")
			(hide yes)
			(effects
				(font
					(size 1.27 1.27)
				)
			)
		)
		(property "Value" "SCD22U10V2KX-1GP"
			(at 1.1811 -2.7051 180)
			(unlocked yes)
			(layer "F.Fab")
			(hide yes)
			(effects
				(font
					(size 1.016 1.016)
					(thickness 0.1524)
				)
			)
		)
		(property "Device Type" "C402H22"
			(at 1.1811 -4.2291 180)
			(unlocked yes)
			(layer "F.Fab")
			(hide yes)
			(effects
				(font
					(size 1.016 1.016)
					(thickness 0.1524)
				)
			)
		)
		(duplicate_pad_numbers_are_jumpers no)
		(fp_rect
			(start -0.4318 0.9525)
			(end 0.4318 -0.9525)
			(stroke
				(width 0)
				(type default)
			)
			(fill no)
			(layer "F.CrtYd")
		)
		(fp_rect
			(start -0.4318 0.9525)
			(end 0.4318 -0.9525)
			(stroke
				(width 0)
				(type default)
			)
			(fill no)
			(layer "F.Fab")
		)
		(pad "1" smd custom
			(at 0 -0.4445 180)
			(size 0.1524 0.1524)
			(layers "F.Cu" "F.Mask" "F.Paste")
			(net "PCIE_TX_CAP_N30")
			(options
				(clearance outline)
				(anchor circle)
			)
			(primitives
				(gr_poly
					(pts
						(arc
							(start 0.3048 -0.2032)
							(mid 0.275042 -0.275042)
							(end 0.2032 -0.3048)
						)
						(arc
							(start -0.2032 -0.3048)
							(mid -0.275042 -0.275042)
							(end -0.3048 -0.2032)
						)
						(arc
							(start -0.3048 0.2032)
							(mid -0.275042 0.275042)
							(end -0.2032 0.3048)
						)
						(arc
							(start 0.2032 0.3048)
							(mid 0.275042 0.275042)
							(end 0.3048 0.2032)
						)
					)
					(width 0)
					(fill yes)
				)
			)
		)
		(pad "2" smd custom
			(at 0 0.4445 180)
			(size 0.1524 0.1524)
			(layers "F.Cu" "F.Mask" "F.Paste")
			(net "PCIE_TX_N30")
			(options
				(clearance outline)
				(anchor circle)
			)
			(primitives
				(gr_poly
					(pts
						(arc
							(start 0.3048 -0.2032)
							(mid 0.275042 -0.275042)
							(end 0.2032 -0.3048)
						)
						(arc
							(start -0.2032 -0.3048)
							(mid -0.275042 -0.275042)
							(end -0.3048 -0.2032)
						)
						(arc
							(start -0.3048 0.2032)
							(mid -0.275042 0.275042)
							(end -0.2032 0.3048)
						)
						(arc
							(start 0.2032 0.3048)
							(mid 0.275042 0.275042)
							(end 0.3048 0.2032)
						)
					)
					(width 0)
					(fill yes)
				)
			)
		)
	)
)
